# S9S_MB_2U (Grand Teton) — schematic netlist excerpt (pin names and nets, part order shuffled) for the footprints in the layout excerpt that follows; sources: Cadence DE-HDL packaged netlist, KiCad conversion of 03242023_DA0F0TMBIJ0_F0T_Motherboard_J_brd_V01_OCP.brd

C722  Q_CAP_DIFFBUS  DIFF BUS_0.22UF 6.3V 20% X6S  pkg C0201  page 176 : \1\ = P5E_CPU1_PE0_TX_C_DN<9> ; \2\ = P5E_CPU1_PE0_TX_DN<9>
C1840  Q_CAP  0.1UF 25V 10% X7R  pkg 0402  page 154 : A = P3V3_AUX ; B = GND
C972  Q_CAP  10UF 6.3V 20% X6S  pkg C0402  page 74 : A = PVCCIN_CPU0 ; B = GND

(kicad_pcb
	(version 20260206)
	(generator "pcbnew")
	(generator_version "10.0")
	(general
		(thickness 1.6)
		(legacy_teardrops no)
	)
	(paper "A4")
	(title_block
		(title "03242023_DA0F0TMBIJ0_F0T_Motherboard_J_brd_V01_OCP.brd")
		(comment 1 "Grand Teton / footprints 940-942 of 6105")
	)
	(layers
		(0 "F.Cu" signal "TOP")
		(4 "In1.Cu" signal "GND")
		(6 "In2.Cu" signal "IN1")
		(8 "In3.Cu" signal "GND1")
		(10 "In4.Cu" signal "IN2")
		(12 "In5.Cu" signal "GND2")
		(14 "In6.Cu" signal "IN3")
		(16 "In7.Cu" signal "GND3")
		(18 "In8.Cu" signal "VCC")
		(20 "In9.Cu" signal "VCC1")
		(22 "In10.Cu" signal "GND4")
		(24 "In11.Cu" signal "IN4")
		(26 "In12.Cu" signal "GND5")
		(28 "In13.Cu" signal "IN5")
		(30 "In14.Cu" signal "GND6")
		(32 "In15.Cu" signal "IN6")
		(34 "In16.Cu" signal "GND7")
		(2 "B.Cu" signal "BOTTOM")
		(9 "F.Adhes" user "F.Adhesive")
		(11 "B.Adhes" user "B.Adhesive")
		(13 "F.Paste" user "Package Geometry/Pastemask Top")
		(15 "B.Paste" user "Package Geometry/Pastemask Bottom")
		(5 "F.SilkS" user "Ref Des/Silkscreen Top")
		(7 "B.SilkS" user "Ref Des/Silkscreen Bottom")
		(1 "F.Mask" user "Board Geometry/Soldermask Top")
		(3 "B.Mask" user "Board Geometry/Soldermask Bottom")
		(17 "Dwgs.User" user "User.Drawings")
		(19 "Cmts.User" user "User.Comments")
		(21 "Eco1.User" user "User.Eco1")
		(23 "Eco2.User" user "User.Eco2")
		(25 "Edge.Cuts" user "Board Geometry/Outline")
		(27 "Margin" user)
		(31 "F.CrtYd" user "Package Geometry/Place Bound Top")
		(29 "B.CrtYd" user "Package Geometry/Place Bound Bottom")
		(35 "F.Fab" user "Ref Des/Assembly Top")
		(33 "B.Fab" user "Ref Des/Assembly Bottom")
	)
	(footprint ""
		(layer "F.Cu")
		(at 365.46663 -258.726686 90)
		(property "Reference" "C972"
			(at 0 0 90)
			(layer "F.SilkS")
			(hide yes)
			(effects
				(font
					(size 1.27 1.27)
				)
			)
		)
		(property "Value" ""
			(at 0 0 90)
			(layer "F.Fab")
			(effects
				(font
					(size 1.27 1.27)
				)
			)
		)
		(duplicate_pad_numbers_are_jumpers no)
		(fp_line
			(start 0.7874 -0.4064)
			(end 0.7874 0.4064)
			(stroke
				(width 0.1524)
				(type default)
			)
			(layer "F.SilkS")
		)
		(fp_line
			(start -0.7874 -0.4064)
			(end 0.7874 -0.4064)
			(stroke
				(width 0.1524)
				(type default)
			)
			(layer "F.SilkS")
		)
		(fp_line
			(start 0.7874 0.4064)
			(end -0.7874 0.4064)
			(stroke
				(width 0.1524)
				(type default)
			)
			(layer "F.SilkS")
		)
		(fp_line
			(start -0.7874 0.4064)
			(end -0.7874 -0.4064)
			(stroke
				(width 0.1524)
				(type default)
			)
			(layer "F.SilkS")
		)
		(fp_line
			(start -0.12065 -0.305054)
			(end -0.12065 -0.2794)
			(stroke
				(width 0.1)
				(type default)
			)
			(layer "F.Fab")
		)
		(fp_line
			(start -0.67945 -0.305054)
			(end -0.12065 -0.305054)
			(stroke
				(width 0.1)
				(type default)
			)
			(layer "F.Fab")
		)
		(fp_line
			(start 0.67945 -0.3048)
			(end 0.67945 0.3048)
			(stroke
				(width 0.1)
				(type default)
			)
			(layer "F.Fab")
		)
		(fp_line
			(start 0.12065 -0.3048)
			(end 0.67945 -0.3048)
			(stroke
				(width 0.1)
				(type default)
			)
			(layer "F.Fab")
		)
		(fp_line
			(start 0.12065 -0.2794)
			(end 0.12065 -0.3048)
			(stroke
				(width 0.1)
				(type default)
			)
			(layer "F.Fab")
		)
		(fp_line
			(start -0.12065 -0.2794)
			(end 0.12065 -0.2794)
			(stroke
				(width 0.1)
				(type default)
			)
			(layer "F.Fab")
		)
		(fp_line
			(start 0.120396 0.2794)
			(end -0.12065 0.2794)
			(stroke
				(width 0.1)
				(type default)
			)
			(layer "F.Fab")
		)
		(fp_line
			(start -0.12065 0.2794)
			(end -0.12065 0.3048)
			(stroke
				(width 0.1)
				(type default)
			)
			(layer "F.Fab")
		)
		(fp_line
			(start 0.67945 0.3048)
			(end 0.120396 0.3048)
			(stroke
				(width 0.1)
				(type default)
			)
			(layer "F.Fab")
		)
		(fp_line
			(start 0.120396 0.3048)
			(end 0.120396 0.2794)
			(stroke
				(width 0.1)
				(type default)
			)
			(layer "F.Fab")
		)
		(fp_line
			(start -0.12065 0.3048)
			(end -0.67945 0.3048)
			(stroke
				(width 0.1)
				(type default)
			)
			(layer "F.Fab")
		)
		(fp_line
			(start -0.67945 0.3048)
			(end -0.67945 -0.305054)
			(stroke
				(width 0.1)
				(type default)
			)
			(layer "F.Fab")
		)
		(pad "1" smd circle
			(at -0.40005 0 90)
			(size 0 0)
			(layers "F.Cu" "F.Mask" "F.Paste")
			(net "PVCCIN_CPU0")
		)
		(pad "2" smd circle
			(at 0.40005 0 90)
			(size 0 0)
			(layers "F.Cu" "F.Mask" "F.Paste")
			(net "GND")
		)
	)
	(footprint ""
		(layer "F.Cu")
		(at 66.333878 -402.371052 -90)
		(property "Reference" "C722"
			(at 0 0 270)
			(layer "F.SilkS")
			(hide yes)
			(effects
				(font
					(size 1.27 1.27)
				)
			)
		)
		(property "Value" ""
			(at 0 0 270)
			(layer "F.Fab")
			(effects
				(font
					(size 1.27 1.27)
				)
			)
		)
		(duplicate_pad_numbers_are_jumpers no)
		(fp_line
			(start -0.299974 0.150114)
			(end -0.299974 -0.150114)
			(stroke
				(width 0.1)
				(type default)
			)
			(layer "F.Fab")
		)
		(fp_line
			(start 0.299974 0.150114)
			(end -0.299974 0.150114)
			(stroke
				(width 0.1)
				(type default)
			)
			(layer "F.Fab")
		)
		(fp_line
			(start -0.299974 -0.150114)
			(end 0.299974 -0.150114)
			(stroke
				(width 0.1)
				(type default)
			)
			(layer "F.Fab")
		)
		(fp_line
			(start 0.299974 -0.150114)
			(end 0.299974 0.150114)
			(stroke
				(width 0.1)
				(type default)
			)
			(layer "F.Fab")
		)
		(pad "1" smd rect
			(at -0.2667 0 270)
			(size 0.3048 0.381)
			(layers "F.Cu" "F.Mask" "F.Paste")
			(net "P5E_CPU1_PE0_TX_C_DN<9>")
		)
		(pad "2" smd rect
			(at 0.2667 0 270)
			(size 0.3048 0.381)
			(layers "F.Cu" "F.Mask" "F.Paste")
			(net "P5E_CPU1_PE0_TX_DN<9>")
		)
	)
	(footprint ""
		(layer "F.Cu")
		(at 461.957928 -94.317566)
		(property "Reference" "C1840"
			(at 0 0 0)
			(layer "F.SilkS")
			(hide yes)
			(effects
				(font
					(size 1.27 1.27)
				)
			)
		)
		(property "Value" ""
			(at 0 0 0)
			(layer "F.Fab")
			(effects
				(font
					(size 1.27 1.27)
				)
			)
		)
		(duplicate_pad_numbers_are_jumpers no)
		(fp_line
			(start -0.7874 -0.4064)
			(end 0.7874 -0.4064)
			(stroke
				(width 0.1524)
				(type default)
			)
			(layer "F.SilkS")
		)
		(fp_line
			(start -0.7874 0.4064)
			(end -0.7874 -0.4064)
			(stroke
				(width 0.1524)
				(type default)
			)
			(layer "F.SilkS")
		)
		(fp_line
			(start 0.7874 -0.4064)
			(end 0.7874 0.4064)
			(stroke
				(width 0.1524)
				(type default)
			)
			(layer "F.SilkS")
		)
		(fp_line
			(start 0.7874 0.4064)
			(end -0.7874 0.4064)
			(stroke
				(width 0.1524)
				(type default)
			)
			(layer "F.SilkS")
		)
		(fp_line
			(start -0.67945 -0.305054)
			(end -0.12065 -0.305054)
			(stroke
				(width 0.1)
				(type default)
			)
			(layer "F.Fab")
		)
		(fp_line
			(start -0.67945 0.3048)
			(end -0.67945 -0.305054)
			(stroke
				(width 0.1)
				(type default)
			)
			(layer "F.Fab")
		)
		(fp_line
			(start -0.12065 -0.305054)
			(end -0.12065 -0.2794)
			(stroke
				(width 0.1)
				(type default)
			)
			(layer "F.Fab")
		)
		(fp_line
			(start -0.12065 -0.2794)
			(end 0.12065 -0.2794)
			(stroke
				(width 0.1)
				(type default)
			)
			(layer "F.Fab")
		)
		(fp_line
			(start -0.12065 0.2794)
			(end -0.12065 0.3048)
			(stroke
				(width 0.1)
				(type default)
			)
			(layer "F.Fab")
		)
		(fp_line
			(start -0.12065 0.3048)
			(end -0.67945 0.3048)
			(stroke
				(width 0.1)
				(type default)
			)
			(layer "F.Fab")
		)
		(fp_line
			(start 0.120396 0.2794)
			(end -0.12065 0.2794)
			(stroke
				(width 0.1)
				(type default)
			)
			(layer "F.Fab")
		)
		(fp_line
			(start 0.120396 0.3048)
			(end 0.120396 0.2794)
			(stroke
				(width 0.1)
				(type default)
			)
			(layer "F.Fab")
		)
		(fp_line
			(start 0.12065 -0.3048)
			(end 0.67945 -0.3048)
			(stroke
				(width 0.1)
				(type default)
			)
			(layer "F.Fab")
		)
		(fp_line
			(start 0.12065 -0.2794)
			(end 0.12065 -0.3048)
			(stroke
				(width 0.1)
				(type default)
			)
			(layer "F.Fab")
		)
		(fp_line
			(start 0.67945 -0.3048)
			(end 0.67945 0.3048)
			(stroke
				(width 0.1)
				(type default)
			)
			(layer "F.Fab")
		)
		(fp_line
			(start 0.67945 0.3048)
			(end 0.120396 0.3048)
			(stroke
				(width 0.1)
				(type default)
			)
			(layer "F.Fab")
		)
		(pad "1" smd circle
			(at -0.40005 0)
			(size 0 0)
			(layers "F.Cu" "F.Mask" "F.Paste")
			(net "P3V3_AUX")
		)
		(pad "2" smd circle
			(at 0.40005 0)
			(size 0 0)
			(layers "F.Cu" "F.Mask" "F.Paste")
			(net "GND")
		)
	)
)
